#ISCELL
  logical_power design_note *
  *
#ISCELL
  mstr_misc dns *
  *
#ISCELL
  pure_quanta quanta_title_block_c *
  *
#ISCELL
  standard offpage *
  page176_i10
#ISCELL
  standard offpage *
  page176_i11
#ISCELL
  standard offpage *
  page176_i118
#ISCELL
  standard offpage *
  page176_i119
#ISCELL
  standard offpage *
  page176_i155
#ISCELL
  standard offpage *
  page176_i156
#ISCELL
  standard offpage *
  page176_i157
#ISCELL
  standard offpage *
  page176_i16
#ISCELL
  logical_power universal_gnd *
  page176_i161
#ISCELL
  logical_power universal_gnd *
  page176_i163
#ISCELL
  logical_power universal_power *
  page176_i168
#ISCELL
  standard offpage *
  page176_i17
#ISCELL
  standard offpage *
  page176_i171
#ISCELL
  standard offpage *
  page176_i172
#CELL
  pure_quanta q_res *
  page176_i173
#CELL
  pure_quanta q_res *
  page176_i174
#CELL
  pure_quanta q_res *
  page176_i175
#CELL
  pure_quanta q_res *
  page176_i176
#ISCELL
  standard offpage *
  page176_i177
#ISCELL
  standard offpage *
  page176_i179
#ISCELL
  standard offpage *
  page176_i180
#ISCELL
  standard offpage *
  page176_i181
#CELL
  pure_quanta q_res *
  page176_i183
#CELL
  pure_quanta q_res *
  page176_i184
#CELL
  pure_quanta q_res *
  page176_i185
#CELL
  pure_quanta q_res *
  page176_i186
#ISCELL
  standard offpage *
  page176_i188
#ISCELL
  standard offpage *
  page176_i189
#ISCELL
  standard offpage *
  page176_i190
#ISCELL
  standard offpage *
  page176_i191
#CELL
  pure_quanta q_res *
  page176_i195
#CELL
  pure_quanta q_res *
  page176_i196
#CELL
  pure_quanta q_res *
  page176_i197
#ISCELL
  standard offpage *
  page176_i198
#ISCELL
  standard offpage *
  page176_i199
#ISCELL
  standard offpage *
  page176_i2
#ISCELL
  standard offpage *
  page176_i20
#ISCELL
  standard offpage *
  page176_i200
#CELL
  pure_quanta q_res *
  page176_i201
#CELL
  pure_quanta q_res *
  page176_i202
#CELL
  pure_quanta q_res *
  page176_i203
#CELL
  pure_quanta q_res *
  page176_i204
#CELL
  pure_quanta q_res *
  page176_i205
#CELL
  pure_quanta q_res *
  page176_i206
#CELL
  pure_quanta q_res *
  page176_i207
#ISCELL
  logical_power universal_gnd *
  page176_i208
#CELL
  pure_quanta q_res *
  page176_i209
#ISCELL
  standard offpage *
  page176_i21
#ISCELL
  standard offpage *
  page176_i210
#ISCELL
  standard offpage *
  page176_i211
#ISCELL
  standard offpage *
  page176_i212
#ISCELL
  standard offpage *
  page176_i213
#ISCELL
  standard offpage *
  page176_i214
#ISCELL
  standard offpage *
  page176_i215
#ISCELL
  standard offpage *
  page176_i216
#ISCELL
  standard offpage *
  page176_i217
#CELL
  pure_quanta emmitsburg_rev0p9 *
  page176_i22
#ISCELL
  standard offpage *
  page176_i225
#ISCELL
  standard offpage *
  page176_i226
#ISCELL
  standard offpage *
  page176_i227
#ISCELL
  standard offpage *
  page176_i228
#ISCELL
  standard offpage *
  page176_i229
#ISCELL
  standard offpage *
  page176_i23
#ISCELL
  standard offpage *
  page176_i230
#ISCELL
  standard offpage *
  page176_i231
#ISCELL
  standard offpage *
  page176_i232
#ISCELL
  standard offpage *
  page176_i233
#ISCELL
  standard offpage *
  page176_i234
#ISCELL
  standard offpage *
  page176_i235
#ISCELL
  standard offpage *
  page176_i237
#ISCELL
  standard offpage *
  page176_i238
#CELL
  pure_quanta q_res *
  page176_i239
#ISCELL
  standard offpage *
  page176_i24
#CELL
  pure_quanta q_res *
  page176_i240
#ISCELL
  standard offpage *
  page176_i243
#ISCELL
  standard offpage *
  page176_i244
#ISCELL
  standard offpage *
  page176_i245
#CELL
  pure_quanta q_res *
  page176_i246
#ISCELL
  logical_power universal_power *
  page176_i247
#ISCELL
  standard offpage *
  page176_i248
#ISCELL
  standard offpage *
  page176_i25
#ISCELL
  standard offpage *
  page176_i26
#ISCELL
  standard offpage *
  page176_i31
#ISCELL
  standard offpage *
  page176_i32
#ISCELL
  standard offpage *
  page176_i34
#ISCELL
  standard offpage *
  page176_i39
#ISCELL
  standard offpage *
  page176_i40
#ISCELL
  standard offpage *
  page176_i41
#ISCELL
  standard offpage *
  page176_i42
#ISCELL
  standard offpage *
  page176_i43
#ISCELL
  standard offpage *
  page176_i44
#ISCELL
  standard offpage *
  page176_i46
#ISCELL
  standard offpage *
  page176_i47
#ISCELL
  standard offpage *
  page176_i48
#ISCELL
  standard offpage *
  page176_i53
#ISCELL
  standard offpage *
  page176_i75
#ISCELL
  standard offpage *
  page176_i76
#ISCELL
  standard offpage *
  page176_i94
#ISCELL
  standard offpage *
  page176_i95
